(kicad_pcb
	(version 20260206)
	(generator "pcbnew")
	(generator_version "10.0")
	(general
		(thickness 1.6)
		(legacy_teardrops no)
	)
	(paper "A4")
	(title_block
		(title "04192023_DAF0TMB3IC0_F0TG_MB_C_brd_V02_OCP.brd")
		(comment 1 "Grand Teton / footprints 3221-3227 of 8354")
	)
	(layers
		(0 "F.Cu" signal "TOP")
		(4 "In1.Cu" signal "GND")
		(6 "In2.Cu" signal "IN1")
		(8 "In3.Cu" signal "GND1")
		(10 "In4.Cu" signal "IN2")
		(12 "In5.Cu" signal "GND2")
		(14 "In6.Cu" signal "IN3")
		(16 "In7.Cu" signal "GND3")
		(18 "In8.Cu" signal "VCC")
		(20 "In9.Cu" signal "VCC1")
		(22 "In10.Cu" signal "GND4")
		(24 "In11.Cu" signal "IN4")
		(26 "In12.Cu" signal "GND5")
		(28 "In13.Cu" signal "IN5")
		(30 "In14.Cu" signal "GND6")
		(32 "In15.Cu" signal "IN6")
		(34 "In16.Cu" signal "GND7")
		(2 "B.Cu" signal "BOTTOM")
		(9 "F.Adhes" user "F.Adhesive")
		(11 "B.Adhes" user "B.Adhesive")
		(13 "F.Paste" user "Package Geometry/Pastemask Top")
		(15 "B.Paste" user "Package Geometry/Pastemask Bottom")
		(5 "F.SilkS" user "Ref Des/Silkscreen Top")
		(7 "B.SilkS" user "Ref Des/Silkscreen Bottom")
		(1 "F.Mask" user "Board Geometry/Soldermask Top")
		(3 "B.Mask" user "Board Geometry/Soldermask Bottom")
		(17 "Dwgs.User" user "User.Drawings")
		(19 "Cmts.User" user "User.Comments")
		(21 "Eco1.User" user "User.Eco1")
		(23 "Eco2.User" user "User.Eco2")
		(25 "Edge.Cuts" user "Board Geometry/Outline")
		(27 "Margin" user)
		(31 "F.CrtYd" user "Package Geometry/Place Bound Top")
		(29 "B.CrtYd" user "Package Geometry/Place Bound Bottom")
		(35 "F.Fab" user "Ref Des/Assembly Top")
		(33 "B.Fab" user "Ref Des/Assembly Bottom")
	)
	(footprint ""
		(layer "F.Cu")
		(at 122.809 -321.655948 90)
		(property "Reference" "R4305"
			(at 0 0 90)
			(layer "F.SilkS")
			(hide yes)
			(effects
				(font
					(size 1.27 1.27)
				)
			)
		)
		(property "Value" ""
			(at 0 0 90)
			(layer "F.Fab")
			(effects
				(font
					(size 1.27 1.27)
				)
			)
		)
		(duplicate_pad_numbers_are_jumpers no)
		(fp_line
			(start 0.7874 -0.4064)
			(end 0.7874 -0.0508)
			(stroke
				(width 0.1524)
				(type default)
			)
			(layer "F.SilkS")
		)
		(fp_line
			(start -0.7874 -0.4064)
			(end 0.7874 -0.4064)
			(stroke
				(width 0.1524)
				(type default)
			)
			(layer "F.SilkS")
		)
		(fp_line
			(start -0.7874 -0.0508)
			(end -0.7874 -0.4064)
			(stroke
				(width 0.1524)
				(type default)
			)
			(layer "F.SilkS")
		)
		(fp_line
			(start 0.416052 0.4064)
			(end -0.422148 0.4064)
			(stroke
				(width 0.1524)
				(type default)
			)
			(layer "F.SilkS")
		)
		(fp_line
			(start -0.12065 -0.305054)
			(end -0.12065 -0.2794)
			(stroke
				(width 0.1)
				(type default)
			)
			(layer "F.Fab")
		)
		(fp_line
			(start -0.67945 -0.305054)
			(end -0.12065 -0.305054)
			(stroke
				(width 0.1)
				(type default)
			)
			(layer "F.Fab")
		)
		(fp_line
			(start 0.67945 -0.3048)
			(end 0.67945 0.3048)
			(stroke
				(width 0.1)
				(type default)
			)
			(layer "F.Fab")
		)
		(fp_line
			(start 0.12065 -0.3048)
			(end 0.67945 -0.3048)
			(stroke
				(width 0.1)
				(type default)
			)
			(layer "F.Fab")
		)
		(fp_line
			(start 0.12065 -0.2794)
			(end 0.12065 -0.3048)
			(stroke
				(width 0.1)
				(type default)
			)
			(layer "F.Fab")
		)
		(fp_line
			(start -0.12065 -0.2794)
			(end 0.12065 -0.2794)
			(stroke
				(width 0.1)
				(type default)
			)
			(layer "F.Fab")
		)
		(fp_line
			(start 0.120396 0.2794)
			(end -0.12065 0.2794)
			(stroke
				(width 0.1)
				(type default)
			)
			(layer "F.Fab")
		)
		(fp_line
			(start -0.12065 0.2794)
			(end -0.12065 0.3048)
			(stroke
				(width 0.1)
				(type default)
			)
			(layer "F.Fab")
		)
		(fp_line
			(start 0.67945 0.3048)
			(end 0.120396 0.3048)
			(stroke
				(width 0.1)
				(type default)
			)
			(layer "F.Fab")
		)
		(fp_line
			(start 0.120396 0.3048)
			(end 0.120396 0.2794)
			(stroke
				(width 0.1)
				(type default)
			)
			(layer "F.Fab")
		)
		(fp_line
			(start -0.12065 0.3048)
			(end -0.67945 0.3048)
			(stroke
				(width 0.1)
				(type default)
			)
			(layer "F.Fab")
		)
		(fp_line
			(start -0.67945 0.3048)
			(end -0.67945 -0.305054)
			(stroke
				(width 0.1)
				(type default)
			)
			(layer "F.Fab")
		)
		(pad "1" smd circle
			(at -0.40005 0 90)
			(size 0 0)
			(layers "F.Cu" "F.Mask" "F.Paste")
			(net "CLK_100M_CPU1_CLK12_R_DP")
		)
		(pad "2" smd circle
			(at 0.40005 0 90)
			(size 0 0)
			(layers "F.Cu" "F.Mask" "F.Paste")
			(net "CLK_100M_CPU1_CLK12_DP")
		)
	)
	(footprint ""
		(layer "F.Cu")
		(at 112.716056 -340.315042)
		(property "Reference" "H21"
			(at -3.900424 -4.48056 0)
			(unlocked yes)
			(layer "F.SilkS")
			(effects
				(font
					(size 0.7874 0.5842)
					(thickness 0.1524)
				)
				(justify left)
			)
		)
		(property "Value" ""
			(at 0 0 0)
			(layer "F.Fab")
			(effects
				(font
					(size 1.27 1.27)
				)
			)
		)
		(duplicate_pad_numbers_are_jumpers no)
		(pad "1" thru_hole circle
			(at 0 0)
			(size 6.1976 6.1976)
			(drill 3.7338)
			(layers "*.Cu" "*.Mask")
			(remove_unused_layers no)
			(net "GND")
			(clearance -0.9779)
			(padstack
				(mode front_inner_back)
				(layer "Inner"
					(shape circle)
					(size 5.5372 5.5372)
					(clearance -0.6477)
				)
				(layer "B.Cu"
					(shape circle)
					(size 6.1976 6.1976)
					(clearance -0.9779)
				)
			)
		)
	)
	(footprint ""
		(layer "F.Cu")
		(at 127.705104 -55.922164 180)
		(property "Reference" "R6103"
			(at 0 0 180)
			(layer "F.SilkS")
			(hide yes)
			(effects
				(font
					(size 1.27 1.27)
				)
			)
		)
		(property "Value" ""
			(at 0 0 180)
			(layer "F.Fab")
			(effects
				(font
					(size 1.27 1.27)
				)
			)
		)
		(duplicate_pad_numbers_are_jumpers no)
		(fp_line
			(start 0.7874 0.4064)
			(end -0.7874 0.4064)
			(stroke
				(width 0.1524)
				(type default)
			)
			(layer "F.SilkS")
		)
		(fp_line
			(start 0.7874 -0.4064)
			(end 0.7874 0.4064)
			(stroke
				(width 0.1524)
				(type default)
			)
			(layer "F.SilkS")
		)
		(fp_line
			(start -0.7874 0.4064)
			(end -0.7874 -0.4064)
			(stroke
				(width 0.1524)
				(type default)
			)
			(layer "F.SilkS")
		)
		(fp_line
			(start -0.7874 -0.4064)
			(end 0.7874 -0.4064)
			(stroke
				(width 0.1524)
				(type default)
			)
			(layer "F.SilkS")
		)
		(fp_line
			(start 0.67945 0.3048)
			(end 0.120396 0.3048)
			(stroke
				(width 0.1)
				(type default)
			)
			(layer "F.Fab")
		)
		(fp_line
			(start 0.67945 -0.3048)
			(end 0.67945 0.3048)
			(stroke
				(width 0.1)
				(type default)
			)
			(layer "F.Fab")
		)
		(fp_line
			(start 0.12065 -0.2794)
			(end 0.12065 -0.3048)
			(stroke
				(width 0.1)
				(type default)
			)
			(layer "F.Fab")
		)
		(fp_line
			(start 0.12065 -0.3048)
			(end 0.67945 -0.3048)
			(stroke
				(width 0.1)
				(type default)
			)
			(layer "F.Fab")
		)
		(fp_line
			(start 0.120396 0.3048)
			(end 0.120396 0.2794)
			(stroke
				(width 0.1)
				(type default)
			)
			(layer "F.Fab")
		)
		(fp_line
			(start 0.120396 0.2794)
			(end -0.12065 0.2794)
			(stroke
				(width 0.1)
				(type default)
			)
			(layer "F.Fab")
		)
		(fp_line
			(start -0.12065 0.3048)
			(end -0.67945 0.3048)
			(stroke
				(width 0.1)
				(type default)
			)
			(layer "F.Fab")
		)
		(fp_line
			(start -0.12065 0.2794)
			(end -0.12065 0.3048)
			(stroke
				(width 0.1)
				(type default)
			)
			(layer "F.Fab")
		)
		(fp_line
			(start -0.12065 -0.2794)
			(end 0.12065 -0.2794)
			(stroke
				(width 0.1)
				(type default)
			)
			(layer "F.Fab")
		)
		(fp_line
			(start -0.12065 -0.305054)
			(end -0.12065 -0.2794)
			(stroke
				(width 0.1)
				(type default)
			)
			(layer "F.Fab")
		)
		(fp_line
			(start -0.67945 0.3048)
			(end -0.67945 -0.305054)
			(stroke
				(width 0.1)
				(type default)
			)
			(layer "F.Fab")
		)
		(fp_line
			(start -0.67945 -0.305054)
			(end -0.12065 -0.305054)
			(stroke
				(width 0.1)
				(type default)
			)
			(layer "F.Fab")
		)
		(pad "1" smd circle
			(at -0.40005 0 180)
			(size 0 0)
			(layers "F.Cu" "F.Mask" "F.Paste")
			(net "JTAG_CPUX_TDI_R1")
		)
		(pad "2" smd circle
			(at 0.40005 0 180)
			(size 0 0)
			(layers "F.Cu" "F.Mask" "F.Paste")
			(net "JTAG_CPUX_TDI")
		)
	)
	(footprint ""
		(layer "F.Cu")
		(at 65.113154 -370.57203 -90)
		(property "Reference" "C813"
			(at 0 0 270)
			(layer "F.SilkS")
			(hide yes)
			(effects
				(font
					(size 1.27 1.27)
				)
			)
		)
		(property "Value" ""
			(at 0 0 270)
			(layer "F.Fab")
			(effects
				(font
					(size 1.27 1.27)
				)
			)
		)
		(duplicate_pad_numbers_are_jumpers no)
		(fp_line
			(start -0.299974 0.150114)
			(end -0.299974 -0.150114)
			(stroke
				(width 0.1)
				(type default)
			)
			(layer "F.Fab")
		)
		(fp_line
			(start 0.299974 0.150114)
			(end -0.299974 0.150114)
			(stroke
				(width 0.1)
				(type default)
			)
			(layer "F.Fab")
		)
		(fp_line
			(start -0.299974 -0.150114)
			(end 0.299974 -0.150114)
			(stroke
				(width 0.1)
				(type default)
			)
			(layer "F.Fab")
		)
		(fp_line
			(start 0.299974 -0.150114)
			(end 0.299974 0.150114)
			(stroke
				(width 0.1)
				(type default)
			)
			(layer "F.Fab")
		)
		(pad "1" smd rect
			(at -0.2667 0 270)
			(size 0.3048 0.381)
			(layers "F.Cu" "F.Mask" "F.Paste")
			(net "P5E_CPU1_P0_TX_C_DP<12>")
		)
		(pad "2" smd rect
			(at 0.2667 0 270)
			(size 0.3048 0.381)
			(layers "F.Cu" "F.Mask" "F.Paste")
			(net "P5E_CPU1_P0_TX_DP<12>")
		)
	)
	(footprint ""
		(layer "F.Cu")
		(at 403.682962 -62.0395 180)
		(property "Reference" "R478"
			(at 0 0 180)
			(layer "F.SilkS")
			(hide yes)
			(effects
				(font
					(size 1.27 1.27)
				)
			)
		)
		(property "Value" ""
			(at 0 0 180)
			(layer "F.Fab")
			(effects
				(font
					(size 1.27 1.27)
				)
			)
		)
		(duplicate_pad_numbers_are_jumpers no)
		(fp_line
			(start 0.7874 0.4064)
			(end -0.7874 0.4064)
			(stroke
				(width 0.1524)
				(type default)
			)
			(layer "F.SilkS")
		)
		(fp_line
			(start 0.7874 -0.4064)
			(end 0.7874 0.4064)
			(stroke
				(width 0.1524)
				(type default)
			)
			(layer "F.SilkS")
		)
		(fp_line
			(start -0.7874 0.4064)
			(end -0.7874 -0.4064)
			(stroke
				(width 0.1524)
				(type default)
			)
			(layer "F.SilkS")
		)
		(fp_line
			(start -0.7874 -0.4064)
			(end 0.7874 -0.4064)
			(stroke
				(width 0.1524)
				(type default)
			)
			(layer "F.SilkS")
		)
		(fp_line
			(start 0.67945 0.3048)
			(end 0.120396 0.3048)
			(stroke
				(width 0.1)
				(type default)
			)
			(layer "F.Fab")
		)
		(fp_line
			(start 0.67945 -0.3048)
			(end 0.67945 0.3048)
			(stroke
				(width 0.1)
				(type default)
			)
			(layer "F.Fab")
		)
		(fp_line
			(start 0.12065 -0.2794)
			(end 0.12065 -0.3048)
			(stroke
				(width 0.1)
				(type default)
			)
			(layer "F.Fab")
		)
		(fp_line
			(start 0.12065 -0.3048)
			(end 0.67945 -0.3048)
			(stroke
				(width 0.1)
				(type default)
			)
			(layer "F.Fab")
		)
		(fp_line
			(start 0.120396 0.3048)
			(end 0.120396 0.2794)
			(stroke
				(width 0.1)
				(type default)
			)
			(layer "F.Fab")
		)
		(fp_line
			(start 0.120396 0.2794)
			(end -0.12065 0.2794)
			(stroke
				(width 0.1)
				(type default)
			)
			(layer "F.Fab")
		)
		(fp_line
			(start -0.12065 0.3048)
			(end -0.67945 0.3048)
			(stroke
				(width 0.1)
				(type default)
			)
			(layer "F.Fab")
		)
		(fp_line
			(start -0.12065 0.2794)
			(end -0.12065 0.3048)
			(stroke
				(width 0.1)
				(type default)
			)
			(layer "F.Fab")
		)
		(fp_line
			(start -0.12065 -0.2794)
			(end 0.12065 -0.2794)
			(stroke
				(width 0.1)
				(type default)
			)
			(layer "F.Fab")
		)
		(fp_line
			(start -0.12065 -0.305054)
			(end -0.12065 -0.2794)
			(stroke
				(width 0.1)
				(type default)
			)
			(layer "F.Fab")
		)
		(fp_line
			(start -0.67945 0.3048)
			(end -0.67945 -0.305054)
			(stroke
				(width 0.1)
				(type default)
			)
			(layer "F.Fab")
		)
		(fp_line
			(start -0.67945 -0.305054)
			(end -0.12065 -0.305054)
			(stroke
				(width 0.1)
				(type default)
			)
			(layer "F.Fab")
		)
		(pad "1" smd circle
			(at -0.40005 0 180)
			(size 0 0)
			(layers "F.Cu" "F.Mask" "F.Paste")
			(net "CPU0_XTRIG_L5")
		)
		(pad "2" smd circle
			(at 0.40005 0 180)
			(size 0 0)
			(layers "F.Cu" "F.Mask" "F.Paste")
			(net "HDT_CPU0_XTRIG_L5")
		)
	)
	(footprint ""
		(layer "F.Cu")
		(at 366.114076 -75.652122)
		(property "Reference" "ME29"
			(at 0 0 0)
			(layer "F.SilkS")
			(hide yes)
			(effects
				(font
					(size 1.27 1.27)
				)
			)
		)
		(property "Value" ""
			(at 0 0 0)
			(layer "F.Fab")
			(effects
				(font
					(size 1.27 1.27)
				)
			)
		)
		(duplicate_pad_numbers_are_jumpers no)
		(fp_line
			(start 0 -4.99999)
			(end 0 -3.47599)
			(stroke
				(width 0.1524)
				(type default)
			)
			(layer "F.SilkS")
		)
		(fp_line
			(start 0 -1.524)
			(end 0 0)
			(stroke
				(width 0.1524)
				(type default)
			)
			(layer "F.SilkS")
		)
		(fp_line
			(start 0 0)
			(end 1.524 0)
			(stroke
				(width 0.1524)
				(type default)
			)
			(layer "F.SilkS")
		)
		(fp_line
			(start 1.524 -4.99999)
			(end 0 -4.99999)
			(stroke
				(width 0.1524)
				(type default)
			)
			(layer "F.SilkS")
		)
		(fp_line
			(start 13.47597 0)
			(end 14.99997 0)
			(stroke
				(width 0.1524)
				(type default)
			)
			(layer "F.SilkS")
		)
		(fp_line
			(start 14.99997 -4.99999)
			(end 13.47597 -4.99999)
			(stroke
				(width 0.1524)
				(type default)
			)
			(layer "F.SilkS")
		)
		(fp_line
			(start 14.99997 -3.47599)
			(end 14.99997 -4.99999)
			(stroke
				(width 0.1524)
				(type default)
			)
			(layer "F.SilkS")
		)
		(fp_line
			(start 14.99997 0)
			(end 14.99997 -1.524)
			(stroke
				(width 0.1524)
				(type default)
			)
			(layer "F.SilkS")
		)
		(fp_text user "S/N"
			(at 0.1016 -3.54965 0)
			(unlocked yes)
			(layer "F.SilkS")
			(effects
				(font
					(size 1.905 1.4224)
					(thickness 0.1524)
				)
				(justify left)
			)
		)
	)
	(footprint ""
		(layer "F.Cu")
		(at 416.51174 -57.372758)
		(property "Reference" "U240"
			(at -2.3876 -2.250948 0)
			(unlocked yes)
			(layer "F.SilkS")
			(effects
				(font
					(size 0.7874 0.5842)
					(thickness 0.1524)
				)
				(justify left)
			)
		)
		(property "Value" ""
			(at 0 0 0)
			(layer "F.Fab")
			(effects
				(font
					(size 1.27 1.27)
				)
			)
		)
		(duplicate_pad_numbers_are_jumpers no)
		(fp_line
			(start -1.207008 -1.549908)
			(end -1.207008 1.549908)
			(stroke
				(width 0.1524)
				(type default)
			)
			(layer "F.SilkS")
		)
		(fp_line
			(start -1.207008 1.549908)
			(end 1.207008 1.549908)
			(stroke
				(width 0.1524)
				(type default)
			)
			(layer "F.SilkS")
		)
		(fp_line
			(start -0.762508 -1.549908)
			(end -1.207008 -1.549908)
			(stroke
				(width 0.1524)
				(type default)
			)
			(layer "F.SilkS")
		)
		(fp_line
			(start 0 -0.635)
			(end -0.762508 -1.549908)
			(stroke
				(width 0.1524)
				(type default)
			)
			(layer "F.SilkS")
		)
		(fp_line
			(start 0.762508 -1.549908)
			(end 0 -0.635)
			(stroke
				(width 0.1524)
				(type default)
			)
			(layer "F.SilkS")
		)
		(fp_line
			(start 1.207008 -1.549908)
			(end 0.762508 -1.549908)
			(stroke
				(width 0.1524)
				(type default)
			)
			(layer "F.SilkS")
		)
		(fp_line
			(start 1.207008 1.549908)
			(end 1.207008 -1.549908)
			(stroke
				(width 0.1524)
				(type default)
			)
			(layer "F.SilkS")
		)
		(fp_poly
			(pts
				(xy -2.3876 -1.02489) (xy -3.4036 -0.51689) (xy -3.4036 -1.53289)
			)
			(stroke
				(width 0)
				(type default)
			)
			(fill yes)
			(layer "F.SilkS")
		)
		(fp_line
			(start -1.549908 -1.549908)
			(end -1.549908 1.549908)
			(stroke
				(width 0.1)
				(type default)
			)
			(layer "F.Fab")
		)
		(fp_line
			(start -1.549908 1.549908)
			(end 1.549908 1.549908)
			(stroke
				(width 0.1)
				(type default)
			)
			(layer "F.Fab")
		)
		(fp_line
			(start 1.549908 -1.549908)
			(end -1.549908 -1.549908)
			(stroke
				(width 0.1)
				(type default)
			)
			(layer "F.Fab")
		)
		(fp_line
			(start 1.549908 1.549908)
			(end 1.549908 -1.549908)
			(stroke
				(width 0.1)
				(type default)
			)
			(layer "F.Fab")
		)
		(fp_poly
			(pts
				(xy -3.4036 -1.53289) (xy -3.4036 -0.51689) (xy -2.3876 -1.02489)
			)
			(stroke
				(width 0)
				(type default)
			)
			(fill yes)
			(layer "F.Fab")
		)
		(pad "1" smd rect
			(at -1.774952 -1.02489 270)
			(size 0.508 0.8636)
			(layers "F.Cu" "F.Mask" "F.Paste")
			(net "OCP_SFF_PRSNT0_R_N")
		)
		(pad "2" smd rect
			(at -1.774952 -0.32512 270)
			(size 0.4064 0.8636)
			(layers "F.Cu" "F.Mask" "F.Paste")
			(net "OCP_SFF_PRSNT1_R_N")
		)
		(pad "3" smd rect
			(at -1.774952 0.32512 270)
			(size 0.4064 0.8636)
			(layers "F.Cu" "F.Mask" "F.Paste")
			(net "OCP_SFF_PRSNT23_R_N")
		)
		(pad "4" smd rect
			(at -1.774952 1.02489 270)
			(size 0.508 0.8636)
			(layers "F.Cu" "F.Mask" "F.Paste")
			(net "GND")
		)
		(pad "5" smd rect
			(at 1.774952 1.02489 270)
			(size 0.508 0.8636)
			(layers "F.Cu" "F.Mask" "F.Paste")
			(net "OCP_SFF_PRSNT2_R_N")
		)
		(pad "6" smd rect
			(at 1.774952 0.32512 270)
			(size 0.4064 0.8636)
			(layers "F.Cu" "F.Mask" "F.Paste")
			(net "OCP_SFF_PRSNT3_R_N")
		)
		(pad "7" smd rect
			(at 1.774952 -0.32512 270)
			(size 0.4064 0.8636)
			(layers "F.Cu" "F.Mask" "F.Paste")
			(net "OCP_SFF_PRSNT01_R_N")
		)
		(pad "8" smd rect
			(at 1.774952 -1.02489 270)
			(size 0.508 0.8636)
			(layers "F.Cu" "F.Mask" "F.Paste")
			(net "P3V3_AUX")
		)
	)
)
